(kicad_pcb
	(version 20241229)
	(generator "pcbnew")
	(generator_version "9.0")
	(general
		(thickness 1.711)
		(legacy_teardrops no)
	)
	(paper "A4")
	(title_block
		(title "Antmicro Baseboard for Jetson AGX Thor")
		(date "2026-02-18")
		(rev "1.1.0")
		(company "Antmicro Ltd")
		(comment 1 "www.antmicro.com")
		(comment 9 "footprints 938-942 of 1170")
	)
	(layers
		(0 "F.Cu" signal)
		(4 "In1.Cu" signal)
		(6 "In2.Cu" signal)
		(8 "In3.Cu" signal)
		(10 "In4.Cu" jumper)
		(12 "In5.Cu" signal)
		(14 "In6.Cu" signal)
		(16 "In7.Cu" signal)
		(18 "In8.Cu" signal)
		(2 "B.Cu" signal)
		(9 "F.Adhes" user "F.Adhesive")
		(11 "B.Adhes" user "B.Adhesive")
		(13 "F.Paste" user)
		(15 "B.Paste" user)
		(5 "F.SilkS" user "F.Silkscreen")
		(7 "B.SilkS" user "B.Silkscreen")
		(1 "F.Mask" user)
		(3 "B.Mask" user)
		(17 "Dwgs.User" user "User.Drawings")
		(19 "Cmts.User" user "User.Comments")
		(21 "Eco1.User" user "User.Eco1")
		(23 "Eco2.User" user "User.Eco2")
		(25 "Edge.Cuts" user)
		(27 "Margin" user)
		(31 "F.CrtYd" user "F.Courtyard")
		(29 "B.CrtYd" user "B.Courtyard")
		(35 "F.Fab" user)
		(33 "B.Fab" user)
	)
	(footprint "antmicro-footprints:TP_SMD_0.75mm"
		(layer "B.Cu")
		(at 89.7 83.35 -90)
		(property "Reference" "TP100"
			(at 0.45 -0.4 90)
			(layer "B.SilkS")
			(effects
				(font
					(size 0.7 0.7)
					(thickness 0.15)
				)
				(justify left bottom mirror)
			)
		)
		(property "Value" "TP_0.75mm_SMD"
			(at 0 -1.2 90)
			(layer "B.Fab")
			(effects
				(font
					(size 0.7 0.7)
					(thickness 0.15)
				)
				(justify left bottom mirror)
			)
		)
		(property "Description" "SMT test point"
			(at 0 0 90)
			(layer "B.Fab")
			(hide yes)
			(effects
				(font
					(size 1.27 1.27)
					(thickness 0.15)
				)
				(justify mirror)
			)
		)
		(property "MPN" ""
			(at 0 0 90)
			(unlocked yes)
			(layer "B.Fab")
			(hide yes)
			(effects
				(font
					(size 1 1)
					(thickness 0.15)
				)
				(justify mirror)
			)
		)
		(property "Manufacturer" ""
			(at 0 0 90)
			(unlocked yes)
			(layer "B.Fab")
			(hide yes)
			(effects
				(font
					(size 1 1)
					(thickness 0.15)
				)
				(justify mirror)
			)
		)
		(property "Author" "Antmicro"
			(at 0 0 90)
			(unlocked yes)
			(layer "B.Fab")
			(hide yes)
			(effects
				(font
					(size 1 1)
					(thickness 0.15)
				)
				(justify mirror)
			)
		)
		(property "License" "Apache-2.0"
			(at 0 0 90)
			(unlocked yes)
			(layer "B.Fab")
			(hide yes)
			(effects
				(font
					(size 1 1)
					(thickness 0.15)
				)
				(justify mirror)
			)
		)
		(sheetname "/SoM_IO/")
		(sheetfile "som_io.kicad_sch")
		(attr exclude_from_pos_files exclude_from_bom)
		(fp_circle
			(center 0 0)
			(end 0.475 0)
			(stroke
				(width 0.05)
				(type default)
			)
			(fill no)
			(layer "B.CrtYd")
		)
		(fp_text user "${REFERENCE}"
			(at -0.4 -2.7 90)
			(layer "B.Fab")
			(effects
				(font
					(size 0.7 0.7)
					(thickness 0.15)
				)
				(justify left bottom mirror)
			)
		)
		(fp_text user "Author: Antmicro"
			(at -0.4 -3.901 90)
			(layer "B.Fab")
			(effects
				(font
					(size 0.7 0.7)
					(thickness 0.15)
				)
				(justify left bottom mirror)
			)
		)
		(fp_text user "License: Apache-2.0"
			(at -0.4 -5.101 90)
			(layer "B.Fab")
			(effects
				(font
					(size 0.7 0.7)
					(thickness 0.15)
				)
				(justify left bottom mirror)
			)
		)
		(pad "1" smd circle
			(at 0 0 270)
			(size 0.75 0.75)
			(layers "B.Cu" "B.Mask")
			(net 150 "/SoM_IO/I2S_{M.2}.FS")
			(pinfunction "1")
			(pintype "passive")
		)
	)
	(footprint "antmicro-footprints:R_0402_1005Metric"
		(layer "B.Cu")
		(at 238.2 107.824468 180)
		(descr "Resistor SMD 0402")
		(tags "resistor SMD 0402")
		(property "Reference" "R339"
			(at -1.8 -2.375532 0)
			(layer "B.SilkS")
			(effects
				(font
					(size 0.7 0.7)
					(thickness 0.15)
				)
				(justify left bottom mirror)
			)
		)
		(property "Value" "R_0R_0402"
			(at -1.011843 -1.772046 0)
			(layer "B.Fab")
			(effects
				(font
					(size 0.7 0.7)
					(thickness 0.15)
				)
				(justify left bottom mirror)
			)
		)
		(property "Datasheet" "https://industrial.panasonic.com/cdbs/www-data/pdf/RDA0000/AOA0000C301.pdf"
			(at 0 0 0)
			(layer "B.Fab")
			(hide yes)
			(effects
				(font
					(size 1.27 1.27)
					(thickness 0.15)
				)
				(justify mirror)
			)
		)
		(property "Description" "SMD Chip Resistor, Jumper, 0 ohm, 100 mW, 0402 [1005 Metric], Thick Film, General Purpose"
			(at 0 0 0)
			(layer "B.Fab")
			(hide yes)
			(effects
				(font
					(size 1.27 1.27)
					(thickness 0.15)
				)
				(justify mirror)
			)
		)
		(property "MPN" "ERJ2GE0R00X"
			(at 0 0 0)
			(unlocked yes)
			(layer "B.Fab")
			(hide yes)
			(effects
				(font
					(size 1 1)
					(thickness 0.15)
				)
				(justify mirror)
			)
		)
		(property "Manufacturer" "Panasonic"
			(at 0 0 0)
			(unlocked yes)
			(layer "B.Fab")
			(hide yes)
			(effects
				(font
					(size 1 1)
					(thickness 0.15)
				)
				(justify mirror)
			)
		)
		(property "License" "Apache-2.0"
			(at 0 0 0)
			(unlocked yes)
			(layer "B.Fab")
			(hide yes)
			(effects
				(font
					(size 1 1)
					(thickness 0.15)
				)
				(justify mirror)
			)
		)
		(property "Author" "Antmicro"
			(at 0 0 0)
			(unlocked yes)
			(layer "B.Fab")
			(hide yes)
			(effects
				(font
					(size 1 1)
					(thickness 0.15)
				)
				(justify mirror)
			)
		)
		(property "Val" "0R"
			(at 0 0 0)
			(unlocked yes)
			(layer "B.Fab")
			(hide yes)
			(effects
				(font
					(size 1 1)
					(thickness 0.15)
				)
				(justify mirror)
			)
		)
		(property "Tolerance" "~"
			(at 0 0 0)
			(unlocked yes)
			(layer "B.Fab")
			(hide yes)
			(effects
				(font
					(size 1 1)
					(thickness 0.15)
				)
				(justify mirror)
			)
		)
		(property "Current" "1A"
			(at 0 0 0)
			(unlocked yes)
			(layer "B.Fab")
			(hide yes)
			(effects
				(font
					(size 1 1)
					(thickness 0.15)
				)
				(justify mirror)
			)
		)
		(sheetname "/Recovery USB/")
		(sheetfile "recovery_usb.kicad_sch")
		(attr smd)
		(fp_poly
			(pts
				(xy -0.925 0.47) (xy -0.925 -0.47) (xy 0.925 -0.47) (xy 0.925 0.47)
			)
			(stroke
				(width 0.05)
				(type default)
			)
			(fill no)
			(layer "B.CrtYd")
		)
		(fp_poly
			(pts
				(xy -0.5 0.25) (xy -0.5 -0.25) (xy 0.5 -0.25) (xy 0.5 0.25)
			)
			(stroke
				(width 0.15)
				(type solid)
			)
			(fill no)
			(layer "B.Fab")
		)
		(fp_text user "License: Apache-2.0"
			(at -0.949999 -5.169 0)
			(layer "B.Fab")
			(effects
				(font
					(size 0.7 0.7)
					(thickness 0.15)
				)
				(justify left bottom mirror)
			)
		)
		(fp_text user "${REFERENCE}"
			(at -0.95 -3.168 0)
			(layer "B.Fab")
			(effects
				(font
					(size 0.7 0.7)
					(thickness 0.15)
				)
				(justify left bottom mirror)
			)
		)
		(fp_text user "Author: Antmicro"
			(at -0.95 -4.169 0)
			(layer "B.Fab")
			(effects
				(font
					(size 0.7 0.7)
					(thickness 0.15)
				)
				(justify left bottom mirror)
			)
		)
		(pad "1" smd roundrect
			(at -0.48 0 180)
			(size 0.59 0.64)
			(layers "B.Cu" "B.Mask" "B.Paste")
			(roundrect_rratio 0.25)
			(net 1017 "/Recovery USB/USBC2_PEN")
			(pintype "passive")
		)
		(pad "2" smd roundrect
			(at 0.48 0 180)
			(size 0.59 0.64)
			(layers "B.Cu" "B.Mask" "B.Paste")
			(roundrect_rratio 0.25)
			(net 1245 "Net-(R265-Pad1)")
			(pintype "passive")
		)
	)
	(footprint "antmicro-footprints:R_0402_1005Metric"
		(layer "B.Cu")
		(at 216.1 125.5)
		(descr "Resistor SMD 0402")
		(tags "resistor SMD 0402")
		(property "Reference" "R57"
			(at 1 -0.29 0)
			(layer "B.SilkS")
			(effects
				(font
					(size 0.7 0.7)
					(thickness 0.15)
				)
				(justify right top mirror)
			)
		)
		(property "Value" "R_0R_0402"
			(at -1.011843 -1.772047 0)
			(layer "B.Fab")
			(effects
				(font
					(size 0.7 0.7)
					(thickness 0.15)
				)
				(justify right top mirror)
			)
		)
		(property "Datasheet" "https://industrial.panasonic.com/cdbs/www-data/pdf/RDA0000/AOA0000C301.pdf"
			(at 0 0 0)
			(layer "B.Fab")
			(hide yes)
			(effects
				(font
					(size 1.27 1.27)
					(thickness 0.15)
				)
				(justify mirror)
			)
		)
		(property "Description" "SMD Chip Resistor, Jumper, 0 ohm, 100 mW, 0402 [1005 Metric], Thick Film, General Purpose"
			(at 0 0 0)
			(layer "B.Fab")
			(hide yes)
			(effects
				(font
					(size 1.27 1.27)
					(thickness 0.15)
				)
				(justify mirror)
			)
		)
		(property "Manufacturer" "Panasonic"
			(at 0 0 180)
			(unlocked yes)
			(layer "B.Fab")
			(hide yes)
			(effects
				(font
					(size 1 1)
					(thickness 0.15)
				)
				(justify mirror)
			)
		)
		(property "MPN" "ERJ2GE0R00X"
			(at 0 0 180)
			(unlocked yes)
			(layer "B.Fab")
			(hide yes)
			(effects
				(font
					(size 1 1)
					(thickness 0.15)
				)
				(justify mirror)
			)
		)
		(property "Val" "0R"
			(at 0 0 180)
			(unlocked yes)
			(layer "B.Fab")
			(hide yes)
			(effects
				(font
					(size 1 1)
					(thickness 0.15)
				)
				(justify mirror)
			)
		)
		(property "License" "Apache-2.0"
			(at 0 0 180)
			(unlocked yes)
			(layer "B.Fab")
			(hide yes)
			(effects
				(font
					(size 1 1)
					(thickness 0.15)
				)
				(justify mirror)
			)
		)
		(property "Author" "Antmicro"
			(at 0 0 180)
			(unlocked yes)
			(layer "B.Fab")
			(hide yes)
			(effects
				(font
					(size 1 1)
					(thickness 0.15)
				)
				(justify mirror)
			)
		)
		(property "Tolerance" "~"
			(at 0 0 180)
			(unlocked yes)
			(layer "B.Fab")
			(hide yes)
			(effects
				(font
					(size 1 1)
					(thickness 0.15)
				)
				(justify mirror)
			)
		)
		(property "Current" "1A"
			(at 0 0 180)
			(unlocked yes)
			(layer "B.Fab")
			(hide yes)
			(effects
				(font
					(size 1 1)
					(thickness 0.15)
				)
				(justify mirror)
			)
		)
		(sheetname "/USB Hub/")
		(sheetfile "usb_hub.kicad_sch")
		(attr smd)
		(fp_rect
			(start -0.925 0.47)
			(end 0.925 -0.47)
			(stroke
				(width 0.05)
				(type default)
			)
			(fill no)
			(layer "B.CrtYd")
		)
		(fp_rect
			(start -0.5 0.25)
			(end 0.5 -0.25)
			(stroke
				(width 0.15)
				(type solid)
			)
			(fill no)
			(layer "B.Fab")
		)
		(fp_text user "${REFERENCE}"
			(at -0.95 -3.168 0)
			(layer "B.Fab")
			(effects
				(font
					(size 0.7 0.7)
					(thickness 0.15)
				)
				(justify right top mirror)
			)
		)
		(fp_text user "Author: Antmicro"
			(at -0.95 -4.169 0)
			(layer "B.Fab")
			(effects
				(font
					(size 0.7 0.7)
					(thickness 0.15)
				)
				(justify right top mirror)
			)
		)
		(fp_text user "License: Apache-2.0"
			(at -0.95 -5.169 0)
			(layer "B.Fab")
			(effects
				(font
					(size 0.7 0.7)
					(thickness 0.15)
				)
				(justify right top mirror)
			)
		)
		(pad "1" smd roundrect
			(at -0.48 0)
			(size 0.59 0.64)
			(layers "B.Cu" "B.Mask" "B.Paste")
			(roundrect_rratio 0.25)
			(net 1141 "Net-(U21-USB2DN_DM4)")
			(pintype "passive")
		)
		(pad "2" smd roundrect
			(at 0.48 0)
			(size 0.59 0.64)
			(layers "B.Cu" "B.Mask" "B.Paste")
			(roundrect_rratio 0.25)
			(net 2 "+3V3")
			(pintype "passive")
		)
	)
	(footprint "antmicro-footprints:LED_0603_1608Metric_G"
		(layer "B.Cu")
		(at 134.7 55.3 -90)
		(descr "LED SMD 0603 Green")
		(tags "LED SMD 0603 Green")
		(property "Reference" "D44"
			(at -1.08 2.22 90)
			(layer "B.SilkS")
			(effects
				(font
					(size 0.7 0.7)
					(thickness 0.15)
				)
				(justify left bottom mirror)
			)
		)
		(property "Value" "LED_G_0603_LTST-C190GKT"
			(at -0.001 -1.599 90)
			(layer "B.Fab")
			(effects
				(font
					(size 0.7 0.7)
					(thickness 0.15)
				)
				(justify left bottom mirror)
			)
		)
		(property "Datasheet" "https://media.digikey.com/pdf/Data%20Sheets/Lite-On%20PDFs/LTST-C190GKT.pdf"
			(at 0 0 90)
			(layer "B.Fab")
			(hide yes)
			(effects
				(font
					(size 1.27 1.27)
					(thickness 0.15)
				)
				(justify mirror)
			)
		)
		(property "Description" "LED, Green, SMD, 0603, 20 mA, 2.1 V, 569 nm"
			(at 0 0 90)
			(layer "B.Fab")
			(hide yes)
			(effects
				(font
					(size 1.27 1.27)
					(thickness 0.15)
				)
				(justify mirror)
			)
		)
		(property "MPN" "LTST-C190GKT"
			(at 0 0 90)
			(unlocked yes)
			(layer "B.Fab")
			(hide yes)
			(effects
				(font
					(size 1 1)
					(thickness 0.15)
				)
				(justify mirror)
			)
		)
		(property "Manufacturer" "Lite-On"
			(at 0 0 90)
			(unlocked yes)
			(layer "B.Fab")
			(hide yes)
			(effects
				(font
					(size 1 1)
					(thickness 0.15)
				)
				(justify mirror)
			)
		)
		(property "Author" "Antmicro"
			(at 0 0 90)
			(unlocked yes)
			(layer "B.Fab")
			(hide yes)
			(effects
				(font
					(size 1 1)
					(thickness 0.15)
				)
				(justify mirror)
			)
		)
		(property "License" "Apache-2.0"
			(at 0 0 90)
			(unlocked yes)
			(layer "B.Fab")
			(hide yes)
			(effects
				(font
					(size 1 1)
					(thickness 0.15)
				)
				(justify mirror)
			)
		)
		(property "Color" "Green"
			(at 0 0 90)
			(unlocked yes)
			(layer "B.Fab")
			(hide yes)
			(effects
				(font
					(size 1 1)
					(thickness 0.15)
				)
				(justify mirror)
			)
		)
		(sheetname "/Peripherals/")
		(sheetfile "peripherals.kicad_sch")
		(attr smd)
		(fp_line
			(start 0.22 0.35)
			(end -0.22 0.35)
			(stroke
				(width 0.15)
				(type solid)
			)
			(layer "B.SilkS")
		)
		(fp_line
			(start -1.18 0.319)
			(end -1.18 -0.321)
			(stroke
				(width 0.15)
				(type solid)
			)
			(layer "B.SilkS")
		)
		(fp_line
			(start -0.094672 -0.001008)
			(end 0.105329 0.198992)
			(stroke
				(width 0.1)
				(type solid)
			)
			(layer "B.SilkS")
		)
		(fp_line
			(start -0.094672 -0.001008)
			(end -0.24 -0.001008)
			(stroke
				(width 0.1)
				(type solid)
			)
			(layer "B.SilkS")
		)
		(fp_line
			(start 0.105328 -0.001008)
			(end 0.240001 -0.001)
			(stroke
				(width 0.1)
				(type solid)
			)
			(layer "B.SilkS")
		)
		(fp_line
			(start -0.094672 -0.201008)
			(end -0.094672 0.198992)
			(stroke
				(width 0.1)
				(type solid)
			)
			(layer "B.SilkS")
		)
		(fp_line
			(start 0.105328 -0.201008)
			(end 0.105329 0.198992)
			(stroke
				(width 0.1)
				(type solid)
			)
			(layer "B.SilkS")
		)
		(fp_line
			(start 0.105328 -0.201008)
			(end -0.094672 -0.001008)
			(stroke
				(width 0.1)
				(type solid)
			)
			(layer "B.SilkS")
		)
		(fp_line
			(start 0.22 -0.35)
			(end -0.22 -0.35)
			(stroke
				(width 0.15)
				(type solid)
			)
			(layer "B.SilkS")
		)
		(fp_poly
			(pts
				(xy 1.25 -0.65) (xy 1.25 0.65) (xy -1.25 0.65) (xy -1.25 -0.65)
			)
			(stroke
				(width 0.05)
				(type solid)
			)
			(fill no)
			(layer "B.CrtYd")
		)
		(fp_line
			(start -0.199 0.202)
			(end -0.199 -0.1)
			(stroke
				(width 0.15)
				(type solid)
			)
			(layer "B.Fab")
		)
		(fp_line
			(start 0.201 0.202)
			(end -0.101 0)
			(stroke
				(width 0.15)
				(type solid)
			)
			(layer "B.Fab")
		)
		(fp_line
			(start -0.199 0)
			(end -0.597 0)
			(stroke
				(width 0.15)
				(type solid)
			)
			(layer "B.Fab")
		)
		(fp_line
			(start -0.101 0)
			(end 0.201 -0.2)
			(stroke
				(width 0.15)
				(type solid)
			)
			(layer "B.Fab")
		)
		(fp_line
			(start 0.200999 0)
			(end 0.201 0.202)
			(stroke
				(width 0.15)
				(type solid)
			)
			(layer "B.Fab")
		)
		(fp_line
			(start 0.599 0)
			(end 0.200999 0)
			(stroke
				(width 0.15)
				(type solid)
			)
			(layer "B.Fab")
		)
		(fp_line
			(start -0.199 -0.2)
			(end -0.199 -0.1)
			(stroke
				(width 0.15)
				(type solid)
			)
			(layer "B.Fab")
		)
		(fp_line
			(start 0.201 -0.2)
			(end 0.200999 0)
			(stroke
				(width 0.15)
				(type solid)
			)
			(layer "B.Fab")
		)
		(fp_poly
			(pts
				(xy 0.848 -0.4) (xy 0.848 0.401999) (xy -0.85 0.402) (xy -0.85 -0.4)
			)
			(stroke
				(width 0.15)
				(type solid)
			)
			(fill no)
			(layer "B.Fab")
		)
		(fp_text user "License: Apache-2.0"
			(at -1.4224 -3.599 90)
			(layer "B.Fab")
			(effects
				(font
					(size 0.7 0.7)
					(thickness 0.15)
				)
				(justify left bottom mirror)
			)
		)
		(fp_text user "Author: Antmicro"
			(at -1.4224 -4.799 90)
			(layer "B.Fab")
			(effects
				(font
					(size 0.7 0.7)
					(thickness 0.15)
				)
				(justify left bottom mirror)
			)
		)
		(fp_text user "${REFERENCE}"
			(at -1.4224 -5.999 90)
			(layer "B.Fab")
			(effects
				(font
					(size 0.7 0.7)
					(thickness 0.15)
				)
				(justify left bottom mirror)
			)
		)
		(pad "1" smd roundrect
			(at -0.7 0 90)
			(size 0.8 1)
			(layers "B.Cu" "B.Mask" "B.Paste")
			(roundrect_rratio 0.2)
			(net 1 "GND")
			(pinfunction "C")
			(pintype "passive")
		)
		(pad "2" smd roundrect
			(at 0.7 0 90)
			(size 0.8 1)
			(layers "B.Cu" "B.Mask" "B.Paste")
			(roundrect_rratio 0.2)
			(net 548 "Net-(D44-A)")
			(pinfunction "A")
			(pintype "passive")
		)
	)
	(footprint "antmicro-footprints:R_0402_1005Metric"
		(layer "B.Cu")
		(at 191.12 121.7 90)
		(descr "Resistor SMD 0402")
		(tags "resistor SMD 0402")
		(property "Reference" "R99"
			(at -3 -0.42 90)
			(layer "B.SilkS")
			(effects
				(font
					(size 0.7 0.7)
					(thickness 0.15)
				)
				(justify right top mirror)
			)
		)
		(property "Value" "R_0R_0402"
			(at -1.011843 -1.772047 90)
			(layer "B.Fab")
			(effects
				(font
					(size 0.7 0.7)
					(thickness 0.15)
				)
				(justify right top mirror)
			)
		)
		(property "Datasheet" "https://industrial.panasonic.com/cdbs/www-data/pdf/RDA0000/AOA0000C301.pdf"
			(at 0 0 90)
			(layer "B.Fab")
			(hide yes)
			(effects
				(font
					(size 1.27 1.27)
					(thickness 0.15)
				)
				(justify mirror)
			)
		)
		(property "Description" "SMD Chip Resistor, Jumper, 0 ohm, 100 mW, 0402 [1005 Metric], Thick Film, General Purpose"
			(at 0 0 90)
			(layer "B.Fab")
			(hide yes)
			(effects
				(font
					(size 1.27 1.27)
					(thickness 0.15)
				)
				(justify mirror)
			)
		)
		(property "MPN" "ERJ2GE0R00X"
			(at 0 0 270)
			(unlocked yes)
			(layer "B.Fab")
			(hide yes)
			(effects
				(font
					(size 1 1)
					(thickness 0.15)
				)
				(justify mirror)
			)
		)
		(property "Manufacturer" "Panasonic"
			(at 0 0 270)
			(unlocked yes)
			(layer "B.Fab")
			(hide yes)
			(effects
				(font
					(size 1 1)
					(thickness 0.15)
				)
				(justify mirror)
			)
		)
		(property "License" "Apache-2.0"
			(at 0 0 270)
			(unlocked yes)
			(layer "B.Fab")
			(hide yes)
			(effects
				(font
					(size 1 1)
					(thickness 0.15)
				)
				(justify mirror)
			)
		)
		(property "Author" "Antmicro"
			(at 0 0 270)
			(unlocked yes)
			(layer "B.Fab")
			(hide yes)
			(effects
				(font
					(size 1 1)
					(thickness 0.15)
				)
				(justify mirror)
			)
		)
		(property "Val" "0R"
			(at 0 0 270)
			(unlocked yes)
			(layer "B.Fab")
			(hide yes)
			(effects
				(font
					(size 1 1)
					(thickness 0.15)
				)
				(justify mirror)
			)
		)
		(property "Tolerance" "~"
			(at 0 0 270)
			(unlocked yes)
			(layer "B.Fab")
			(hide yes)
			(effects
				(font
					(size 1 1)
					(thickness 0.15)
				)
				(justify mirror)
			)
		)
		(property "Current" "1A"
			(at 0 0 270)
			(unlocked yes)
			(layer "B.Fab")
			(hide yes)
			(effects
				(font
					(size 1 1)
					(thickness 0.15)
				)
				(justify mirror)
			)
		)
		(sheetname "/USB Debug, PD/")
		(sheetfile "usb_debug_pd.kicad_sch")
		(attr smd exclude_from_pos_files exclude_from_bom dnp)
		(fp_rect
			(start -0.925 0.47)
			(end 0.925 -0.47)
			(stroke
				(width 0.05)
				(type default)
			)
			(fill no)
			(layer "B.CrtYd")
		)
		(fp_rect
			(start -0.5 0.25)
			(end 0.5 -0.25)
			(stroke
				(width 0.15)
				(type solid)
			)
			(fill no)
			(layer "B.Fab")
		)
		(fp_text user "Author: Antmicro"
			(at -0.95 -4.169 90)
			(layer "B.Fab")
			(effects
				(font
					(size 0.7 0.7)
					(thickness 0.15)
				)
				(justify right top mirror)
			)
		)
		(fp_text user "License: Apache-2.0"
			(at -0.95 -5.169 90)
			(layer "B.Fab")
			(effects
				(font
					(size 0.7 0.7)
					(thickness 0.15)
				)
				(justify right top mirror)
			)
		)
		(fp_text user "${REFERENCE}"
			(at -0.95 -3.168 90)
			(layer "B.Fab")
			(effects
				(font
					(size 0.7 0.7)
					(thickness 0.15)
				)
				(justify right top mirror)
			)
		)
		(pad "1" smd roundrect
			(at -0.48 0 90)
			(size 0.59 0.64)
			(layers "B.Cu" "B.Mask" "B.Paste")
			(roundrect_rratio 0.25)
			(net 812 "/USB Debug, PD/~{CS}")
			(pintype "passive")
		)
		(pad "2" smd roundrect
			(at 0.48 0 90)
			(size 0.59 0.64)
			(layers "B.Cu" "B.Mask" "B.Paste")
			(roundrect_rratio 0.25)
			(net 929 "/USB Debug, PD/SPI_{HUB_DEBUG}.~{CS0}")
			(pintype "passive")
		)
	)
)
